(kicad_pcb
	(version 20260206)
	(generator "pcbnew")
	(generator_version "10.0")
	(general
		(thickness 1.6)
		(legacy_teardrops no)
	)
	(paper "A4")
	(title_block
		(title "Wiwynn_Tioga_Pass_MB.brd")
		(comment 1 "Tioga Pass / footprints 563-569 of 4770")
	)
	(layers
		(0 "F.Cu" signal "TOP")
		(4 "In1.Cu" signal "L2GND")
		(6 "In2.Cu" signal "L3")
		(8 "In3.Cu" signal "L4GND")
		(10 "In4.Cu" signal "L5")
		(12 "In5.Cu" signal "L6GND")
		(14 "In6.Cu" signal "L7VCC")
		(16 "In7.Cu" signal "L8VCC")
		(18 "In8.Cu" signal "L9GND")
		(20 "In9.Cu" signal "L10")
		(22 "In10.Cu" signal "L11GND")
		(24 "In11.Cu" signal "L12")
		(26 "In12.Cu" signal "L13GND")
		(2 "B.Cu" signal "BOTTOM")
		(9 "F.Adhes" user "F.Adhesive")
		(11 "B.Adhes" user "B.Adhesive")
		(13 "F.Paste" user "Package Geometry/Pastemask Top")
		(15 "B.Paste" user "Package Geometry/Pastemask Bottom")
		(5 "F.SilkS" user "Ref Des/Silkscreen Top")
		(7 "B.SilkS" user "Ref Des/Silkscreen Bottom")
		(1 "F.Mask" user "Board Geometry/Soldermask Top")
		(3 "B.Mask" user "Board Geometry/Soldermask Bottom")
		(17 "Dwgs.User" user "User.Drawings")
		(19 "Cmts.User" user "User.Comments")
		(21 "Eco1.User" user "User.Eco1")
		(23 "Eco2.User" user "User.Eco2")
		(25 "Edge.Cuts" user "Board Geometry/Outline")
		(27 "Margin" user)
		(31 "F.CrtYd" user "Package Geometry/Place Bound Top")
		(29 "B.CrtYd" user "Package Geometry/Place Bound Bottom")
		(35 "F.Fab" user "Ref Des/Assembly Top")
		(33 "B.Fab" user "Ref Des/Assembly Bottom")
	)
	(footprint ""
		(layer "F.Cu")
		(at 16.1036 -98.7044 -90)
		(property "Reference" "C1C7"
			(at 0 0 270)
			(layer "F.SilkS")
			(hide yes)
			(effects
				(font
					(size 1.27 1.27)
				)
			)
		)
		(property "Value" ""
			(at 0 0 270)
			(layer "F.Fab")
			(effects
				(font
					(size 1.27 1.27)
				)
			)
		)
		(duplicate_pad_numbers_are_jumpers no)
		(fp_poly
			(pts
				(xy 0.3048 -0.1016) (xy 0.3048 0.9906) (xy -0.3048 0.9906) (xy -0.3048 -0.1016)
			)
			(stroke
				(width 0)
				(type default)
			)
			(fill no)
			(layer "F.CrtYd")
		)
		(fp_line
			(start -0.3048 0.9906)
			(end 0.3048 0.9906)
			(stroke
				(width 0.1)
				(type default)
			)
			(layer "F.Fab")
		)
		(fp_line
			(start 0.3048 0.9906)
			(end 0.3048 -0.1016)
			(stroke
				(width 0.1)
				(type default)
			)
			(layer "F.Fab")
		)
		(fp_line
			(start -0.3048 -0.1016)
			(end -0.3048 0.9906)
			(stroke
				(width 0.1)
				(type default)
			)
			(layer "F.Fab")
		)
		(fp_line
			(start 0.3048 -0.1016)
			(end -0.3048 -0.1016)
			(stroke
				(width 0.1)
				(type default)
			)
			(layer "F.Fab")
		)
		(pad "1" smd rect
			(at 0 0 270)
			(size 0.508 0.508)
			(layers "F.Cu" "F.Mask" "F.Paste")
			(net "VR_PVCCIN_CPU1_VDD")
		)
		(pad "2" smd rect
			(at 0 0.889 270)
			(size 0.508 0.508)
			(layers "F.Cu" "F.Mask" "F.Paste")
			(net "GND")
		)
		(zone
			(layer "F.Cu")
			(hatch none 0.5)
			(connect_pads
				(clearance 0)
			)
			(min_thickness 0.25)
			(keepout
				(tracks not_allowed)
				(vias allowed)
				(pads allowed)
				(copperpour not_allowed)
				(footprints allowed)
			)
			(placement
				(enabled no)
				(sheetname "")
			)
			(fill
				(thermal_gap 0.5)
				(thermal_bridge_width 0.5)
				(island_removal_mode 0)
			)
			(polygon
				(pts
					(xy 15.4686 -98.9584) (xy 15.4686 -98.4504) (xy 15.8496 -98.4504) (xy 15.8496 -98.9584)
				)
			)
		)
		(zone
			(layer "F.Cu")
			(hatch none 0.5)
			(connect_pads
				(clearance 0)
			)
			(min_thickness 0.25)
			(keepout
				(tracks allowed)
				(vias not_allowed)
				(pads allowed)
				(copperpour not_allowed)
				(footprints allowed)
			)
			(placement
				(enabled no)
				(sheetname "")
			)
			(fill
				(thermal_gap 0.5)
				(thermal_bridge_width 0.5)
				(island_removal_mode 0)
			)
			(polygon
				(pts
					(xy 15.8496 -98.9584) (xy 15.8496 -98.4504) (xy 15.4686 -98.4504) (xy 15.4686 -98.9584)
				)
			)
		)
	)
	(footprint ""
		(layer "F.Cu")
		(at 468.493602 -36.626292 -90)
		(property "Reference" "C9F13"
			(at 0 0 270)
			(layer "F.SilkS")
			(hide yes)
			(effects
				(font
					(size 1.27 1.27)
				)
			)
		)
		(property "Value" ""
			(at 0 0 270)
			(layer "F.Fab")
			(effects
				(font
					(size 1.27 1.27)
				)
			)
		)
		(duplicate_pad_numbers_are_jumpers no)
		(fp_poly
			(pts
				(xy -0.7239 -0.2159) (xy 0.7239 -0.2159) (xy 0.7239 1.9939) (xy -0.7239 1.9939)
			)
			(stroke
				(width 0)
				(type default)
			)
			(fill no)
			(layer "F.CrtYd")
		)
		(fp_line
			(start -0.7239 1.9939)
			(end 0.7239 1.9939)
			(stroke
				(width 0.1)
				(type default)
			)
			(layer "F.Fab")
		)
		(fp_line
			(start 0.7239 1.9939)
			(end 0.7239 -0.2159)
			(stroke
				(width 0.1)
				(type default)
			)
			(layer "F.Fab")
		)
		(fp_line
			(start -0.7239 -0.2159)
			(end -0.7239 1.9939)
			(stroke
				(width 0.1)
				(type default)
			)
			(layer "F.Fab")
		)
		(fp_line
			(start 0.7239 -0.2159)
			(end -0.7239 -0.2159)
			(stroke
				(width 0.1)
				(type default)
			)
			(layer "F.Fab")
		)
		(pad "1" smd rect
			(at 0 0 270)
			(size 1.27 1.016)
			(layers "F.Cu" "F.Mask" "F.Paste")
			(net "P1V2_AUX_BMC")
		)
		(pad "2" smd rect
			(at 0 1.778 270)
			(size 1.27 1.016)
			(layers "F.Cu" "F.Mask" "F.Paste")
			(net "GND")
		)
		(zone
			(layer "F.Cu")
			(hatch none 0.5)
			(connect_pads
				(clearance 0)
			)
			(min_thickness 0.25)
			(keepout
				(tracks not_allowed)
				(vias allowed)
				(pads allowed)
				(copperpour not_allowed)
				(footprints allowed)
			)
			(placement
				(enabled no)
				(sheetname "")
			)
			(fill
				(thermal_gap 0.5)
				(thermal_bridge_width 0.5)
				(island_removal_mode 0)
			)
			(polygon
				(pts
					(xy 467.985602 -37.261292) (xy 467.985602 -35.991292) (xy 467.223602 -35.991292) (xy 467.223602 -37.261292)
				)
			)
		)
	)
	(footprint ""
		(layer "F.Cu")
		(at 22.66188 -83.24342 180)
		(property "Reference" "R1D14"
			(at 0 0 180)
			(layer "F.SilkS")
			(hide yes)
			(effects
				(font
					(size 1.27 1.27)
				)
			)
		)
		(property "Value" ""
			(at 0 0 180)
			(layer "F.Fab")
			(effects
				(font
					(size 1.27 1.27)
				)
			)
		)
		(duplicate_pad_numbers_are_jumpers no)
		(fp_poly
			(pts
				(xy -0.2794 -0.1016) (xy 0.2794 -0.1016) (xy 0.2794 0.9906) (xy -0.2794 0.9906)
			)
			(stroke
				(width 0)
				(type default)
			)
			(fill no)
			(layer "F.CrtYd")
		)
		(fp_line
			(start 0.2794 0.9906)
			(end 0.2794 -0.1016)
			(stroke
				(width 0.1)
				(type default)
			)
			(layer "F.Fab")
		)
		(fp_line
			(start 0.2794 -0.1016)
			(end -0.2794 -0.1016)
			(stroke
				(width 0.1)
				(type default)
			)
			(layer "F.Fab")
		)
		(fp_line
			(start -0.2794 0.9906)
			(end 0.2794 0.9906)
			(stroke
				(width 0.1)
				(type default)
			)
			(layer "F.Fab")
		)
		(fp_line
			(start -0.2794 -0.1016)
			(end -0.2794 0.9906)
			(stroke
				(width 0.1)
				(type default)
			)
			(layer "F.Fab")
		)
		(pad "1" smd rect
			(at 0 0 180)
			(size 0.508 0.508)
			(layers "F.Cu" "F.Mask" "F.Paste")
			(net "A_HSC_CSOUT")
		)
		(pad "2" smd rect
			(at 0 0.889 180)
			(size 0.508 0.508)
			(layers "F.Cu" "F.Mask" "F.Paste")
			(net "A_HSC_LOW")
		)
		(zone
			(layer "F.Cu")
			(hatch none 0.5)
			(connect_pads
				(clearance 0)
			)
			(min_thickness 0.25)
			(keepout
				(tracks not_allowed)
				(vias allowed)
				(pads allowed)
				(copperpour not_allowed)
				(footprints allowed)
			)
			(placement
				(enabled no)
				(sheetname "")
			)
			(fill
				(thermal_gap 0.5)
				(thermal_bridge_width 0.5)
				(island_removal_mode 0)
			)
			(polygon
				(pts
					(xy 22.91588 -83.87842) (xy 22.40788 -83.87842) (xy 22.40788 -83.49742) (xy 22.91588 -83.49742)
				)
			)
		)
		(zone
			(layer "F.Cu")
			(hatch none 0.5)
			(connect_pads
				(clearance 0)
			)
			(min_thickness 0.25)
			(keepout
				(tracks allowed)
				(vias not_allowed)
				(pads allowed)
				(copperpour not_allowed)
				(footprints allowed)
			)
			(placement
				(enabled no)
				(sheetname "")
			)
			(fill
				(thermal_gap 0.5)
				(thermal_bridge_width 0.5)
				(island_removal_mode 0)
			)
			(polygon
				(pts
					(xy 22.91588 -83.49742) (xy 22.40788 -83.49742) (xy 22.40788 -83.87842) (xy 22.91588 -83.87842)
				)
			)
		)
	)
	(footprint ""
		(layer "F.Cu")
		(at 10.180828 -126.827026 -90)
		(property "Reference" "R12W16"
			(at 0 0 270)
			(layer "F.SilkS")
			(hide yes)
			(effects
				(font
					(size 1.27 1.27)
				)
			)
		)
		(property "Value" "*"
			(at 0 -8.9535 270)
			(unlocked yes)
			(layer "F.Fab")
			(hide yes)
			(effects
				(font
					(size 1.27 1.016)
					(thickness 0.1524)
				)
			)
		)
		(property "Device Type" "665KR5B-1-GP_SMD-RG3-665KR5B-1A"
			(at 0 -10.6299 270)
			(unlocked yes)
			(layer "F.Fab")
			(hide yes)
			(effects
				(font
					(size 1.27 1.016)
					(thickness 0.1524)
				)
			)
		)
		(duplicate_pad_numbers_are_jumpers no)
		(fp_line
			(start -0.889 1.7018)
			(end 0.889 1.7018)
			(stroke
				(width 0.1524)
				(type default)
			)
			(layer "F.SilkS")
		)
		(fp_line
			(start 0.889 1.7018)
			(end 0.889 -0.508)
			(stroke
				(width 0.1524)
				(type default)
			)
			(layer "F.SilkS")
		)
		(fp_line
			(start -0.889 0.0762)
			(end -0.889 1.7018)
			(stroke
				(width 0.1524)
				(type default)
			)
			(layer "F.SilkS")
		)
		(fp_line
			(start -0.889 -1.7018)
			(end -0.889 0.2794)
			(stroke
				(width 0.1524)
				(type default)
			)
			(layer "F.SilkS")
		)
		(fp_line
			(start 0.889 -1.7018)
			(end 0.889 -0.381)
			(stroke
				(width 0.1524)
				(type default)
			)
			(layer "F.SilkS")
		)
		(fp_line
			(start 0.889 -1.7018)
			(end -0.889 -1.7018)
			(stroke
				(width 0.1524)
				(type default)
			)
			(layer "F.SilkS")
		)
		(fp_poly
			(pts
				(xy 0.9652 -1.778) (xy 0.9652 1.778) (xy -0.9652 1.778) (xy -0.9652 -1.778)
			)
			(stroke
				(width 0)
				(type default)
			)
			(fill no)
			(layer "F.CrtYd")
		)
		(fp_rect
			(start -0.9652 1.778)
			(end 0.9652 -1.778)
			(stroke
				(width 0)
				(type default)
			)
			(fill no)
			(layer "F.Fab")
		)
		(pad "1" smd rect
			(at 0 -0.9652 270)
			(size 1.397 1.143)
			(layers "F.Cu" "F.Mask" "F.Paste")
			(net "P12V_STBY")
		)
		(pad "2" smd rect
			(at 0 0.9652 270)
			(size 1.397 1.143)
			(layers "F.Cu" "F.Mask" "F.Paste")
			(net "VR_PVDDQ_KLM_AIINSEN")
		)
	)
	(footprint ""
		(layer "F.Cu")
		(at 400.685 -82.3595 180)
		(property "Reference" "R2P16"
			(at 0 0 180)
			(layer "F.SilkS")
			(hide yes)
			(effects
				(font
					(size 1.27 1.27)
				)
			)
		)
		(property "Value" ""
			(at 0 0 180)
			(layer "F.Fab")
			(effects
				(font
					(size 1.27 1.27)
				)
			)
		)
		(duplicate_pad_numbers_are_jumpers no)
		(fp_poly
			(pts
				(xy -0.2794 -0.1016) (xy 0.2794 -0.1016) (xy 0.2794 0.9906) (xy -0.2794 0.9906)
			)
			(stroke
				(width 0)
				(type default)
			)
			(fill no)
			(layer "F.CrtYd")
		)
		(fp_line
			(start 0.2794 0.9906)
			(end 0.2794 -0.1016)
			(stroke
				(width 0.1)
				(type default)
			)
			(layer "F.Fab")
		)
		(fp_line
			(start 0.2794 -0.1016)
			(end -0.2794 -0.1016)
			(stroke
				(width 0.1)
				(type default)
			)
			(layer "F.Fab")
		)
		(fp_line
			(start -0.2794 0.9906)
			(end 0.2794 0.9906)
			(stroke
				(width 0.1)
				(type default)
			)
			(layer "F.Fab")
		)
		(fp_line
			(start -0.2794 -0.1016)
			(end -0.2794 0.9906)
			(stroke
				(width 0.1)
				(type default)
			)
			(layer "F.Fab")
		)
		(pad "1" smd rect
			(at 0 0 180)
			(size 0.508 0.508)
			(layers "F.Cu" "F.Mask" "F.Paste")
			(net "P3V3_STBY")
		)
		(pad "2" smd rect
			(at 0 0.889 180)
			(size 0.508 0.508)
			(layers "F.Cu" "F.Mask" "F.Paste")
			(net "FM_M2_DET_LVC3")
		)
		(zone
			(layer "F.Cu")
			(hatch none 0.5)
			(connect_pads
				(clearance 0)
			)
			(min_thickness 0.25)
			(keepout
				(tracks not_allowed)
				(vias allowed)
				(pads allowed)
				(copperpour not_allowed)
				(footprints allowed)
			)
			(placement
				(enabled no)
				(sheetname "")
			)
			(fill
				(thermal_gap 0.5)
				(thermal_bridge_width 0.5)
				(island_removal_mode 0)
			)
			(polygon
				(pts
					(xy 400.939 -82.9945) (xy 400.431 -82.9945) (xy 400.431 -82.6135) (xy 400.939 -82.6135)
				)
			)
		)
		(zone
			(layer "F.Cu")
			(hatch none 0.5)
			(connect_pads
				(clearance 0)
			)
			(min_thickness 0.25)
			(keepout
				(tracks allowed)
				(vias not_allowed)
				(pads allowed)
				(copperpour not_allowed)
				(footprints allowed)
			)
			(placement
				(enabled no)
				(sheetname "")
			)
			(fill
				(thermal_gap 0.5)
				(thermal_bridge_width 0.5)
				(island_removal_mode 0)
			)
			(polygon
				(pts
					(xy 400.939 -82.6135) (xy 400.431 -82.6135) (xy 400.431 -82.9945) (xy 400.939 -82.9945)
				)
			)
		)
	)
	(footprint ""
		(layer "F.Cu")
		(at 363.87024 -138.41857 90)
		(property "Reference" "R7A12"
			(at 0 0 90)
			(layer "F.SilkS")
			(hide yes)
			(effects
				(font
					(size 1.27 1.27)
				)
			)
		)
		(property "Value" ""
			(at 0 0 90)
			(layer "F.Fab")
			(effects
				(font
					(size 1.27 1.27)
				)
			)
		)
		(duplicate_pad_numbers_are_jumpers no)
		(fp_rect
			(start -0.2794 -0.1016)
			(end 0.2794 0.9906)
			(stroke
				(width 0)
				(type default)
			)
			(fill no)
			(layer "F.CrtYd")
		)
		(fp_line
			(start 0.2794 -0.1016)
			(end -0.2794 -0.1016)
			(stroke
				(width 0.1)
				(type default)
			)
			(layer "F.Fab")
		)
		(fp_line
			(start -0.2794 -0.1016)
			(end -0.2794 0.9906)
			(stroke
				(width 0.1)
				(type default)
			)
			(layer "F.Fab")
		)
		(fp_line
			(start 0.2794 0.9906)
			(end 0.2794 -0.1016)
			(stroke
				(width 0.1)
				(type default)
			)
			(layer "F.Fab")
		)
		(fp_line
			(start -0.2794 0.9906)
			(end 0.2794 0.9906)
			(stroke
				(width 0.1)
				(type default)
			)
			(layer "F.Fab")
		)
		(pad "1" smd rect
			(at 0 0 90)
			(size 0.508 0.508)
			(layers "F.Cu" "F.Mask" "F.Paste")
			(net "SVID_VDIO_PVDDQ_DEF")
		)
		(pad "2" smd rect
			(at 0 0.889 90)
			(size 0.508 0.508)
			(layers "F.Cu" "F.Mask" "F.Paste")
			(net "SVID_DIO1_CPU0_R")
		)
		(zone
			(layer "F.Cu")
			(hatch none 0.5)
			(connect_pads
				(clearance 0)
			)
			(min_thickness 0.25)
			(keepout
				(tracks allowed)
				(vias not_allowed)
				(pads allowed)
				(copperpour not_allowed)
				(footprints allowed)
			)
			(placement
				(enabled no)
				(sheetname "")
			)
			(fill
				(thermal_gap 0.5)
				(thermal_bridge_width 0.5)
				(island_removal_mode 0)
			)
			(polygon
				(pts
					(xy 364.12424 -138.16457) (xy 364.50524 -138.16457) (xy 364.50524 -138.67257) (xy 364.12424 -138.67257)
				)
			)
		)
		(zone
			(layer "F.Cu")
			(hatch none 0.5)
			(connect_pads
				(clearance 0)
			)
			(min_thickness 0.25)
			(keepout
				(tracks not_allowed)
				(vias allowed)
				(pads allowed)
				(copperpour not_allowed)
				(footprints allowed)
			)
			(placement
				(enabled no)
				(sheetname "")
			)
			(fill
				(thermal_gap 0.5)
				(thermal_bridge_width 0.5)
				(island_removal_mode 0)
			)
			(polygon
				(pts
					(xy 364.12424 -138.16457) (xy 364.50524 -138.16457) (xy 364.50524 -138.67257) (xy 364.12424 -138.67257)
				)
			)
		)
	)
	(footprint ""
		(layer "F.Cu")
		(at 61.285628 -165.04158 -90)
		(property "Reference" "T1D10"
			(at 0 0 270)
			(layer "F.SilkS")
			(hide yes)
			(effects
				(font
					(size 1.27 1.27)
				)
			)
		)
		(property "Value" "*"
			(at -3.4036 -4.46405 270)
			(unlocked yes)
			(layer "F.Fab")
			(hide yes)
			(effects
				(font
					(size 0.889 0.889)
					(thickness 0.1524)
				)
			)
		)
		(property "Device Type" "TEST-PAD-12P-1-GP-U_DISCRET-GBA"
			(at -3.4036 -5.98805 270)
			(unlocked yes)
			(layer "F.Fab")
			(hide yes)
			(effects
				(font
					(size 0.889 0.889)
					(thickness 0.1524)
				)
			)
		)
		(duplicate_pad_numbers_are_jumpers no)
		(fp_line
			(start -2.3876 3.4798)
			(end -2.3876 -4.826)
			(stroke
				(width 0.1524)
				(type default)
			)
			(layer "F.SilkS")
		)
		(fp_line
			(start 2.3622 3.4798)
			(end -2.3876 3.4798)
			(stroke
				(width 0.1524)
				(type default)
			)
			(layer "F.SilkS")
		)
		(fp_line
			(start -2.3876 -4.826)
			(end 2.3622 -4.826)
			(stroke
				(width 0.1524)
				(type default)
			)
			(layer "F.SilkS")
		)
		(fp_line
			(start 2.3622 -4.826)
			(end 2.3622 3.4798)
			(stroke
				(width 0.1524)
				(type default)
			)
			(layer "F.SilkS")
		)
		(fp_rect
			(start -2.6416 3.7338)
			(end 2.6162 -5.08)
			(stroke
				(width 0)
				(type default)
			)
			(fill no)
			(layer "F.CrtYd")
		)
		(fp_rect
			(start -2.6416 3.7338)
			(end 2.6162 -5.08)
			(stroke
				(width 0)
				(type default)
			)
			(fill no)
			(layer "F.Fab")
		)
		(pad "1" smd circle
			(at 0.496824 -1.301496 270)
			(size 0.6604 0.6604)
			(layers "F.Cu" "F.Mask" "F.Paste")
			(net "L12_85OHM_5INCH_DN")
		)
		(pad "2" smd circle
			(at -0.503936 -1.301496 270)
			(size 0.6604 0.6604)
			(layers "F.Cu" "F.Mask" "F.Paste")
			(net "L12_85OHM_5INCH_DP")
		)
		(pad "3" smd custom
			(at -0.00889 0.370078 270)
			(size 0.74295 0.74295)
			(layers "F.Cu" "F.Mask" "F.Paste")
			(net "GND")
			(options
				(clearance outline)
				(anchor circle)
			)
			(primitives
				(gr_poly
					(pts
						(xy -2.1209 1.4859) (xy 2.1209 1.4859) (xy 2.1209 -1.4859) (xy 1.08585 -1.4859) (xy 1.08585 -0.4699)
						(xy -1.08585 -0.4699) (xy -1.08585 -1.4859) (xy -2.1209 -1.4859)
					)
					(width 0)
					(fill yes)
				)
			)
		)
		(pad "4" thru_hole circle
			(at 1.266444 -3.851656 270)
			(size 1.4478 1.4478)
			(drill 1.0414)
			(layers "*.Cu" "*.Mask")
			(remove_unused_layers no)
			(net "GND")
			(clearance 0.1524)
			(thermal_gap 0.1524)
		)
		(pad "5" thru_hole circle
			(at -1.273556 -3.851656 270)
			(size 1.4478 1.4478)
			(drill 1.0414)
			(layers "*.Cu" "*.Mask")
			(remove_unused_layers no)
			(net "GND")
			(clearance 0.1524)
			(thermal_gap 0.1524)
		)
		(pad "6" thru_hole circle
			(at 1.266444 2.498344 270)
			(size 1.4478 1.4478)
			(drill 1.0414)
			(layers "*.Cu" "*.Mask")
			(remove_unused_layers no)
			(net "GND")
			(clearance 0.1524)
			(thermal_gap 0.1524)
		)
		(pad "7" thru_hole circle
			(at -1.273556 2.498344 270)
			(size 1.4478 1.4478)
			(drill 1.0414)
			(layers "*.Cu" "*.Mask")
			(remove_unused_layers no)
			(net "GND")
			(clearance 0.1524)
			(thermal_gap 0.1524)
		)
		(pad "8" thru_hole circle
			(at 1.27 -0.4572 270)
			(size 0.7112 0.7112)
			(drill 0.4064)
			(layers "*.Cu" "*.Mask")
			(remove_unused_layers no)
			(net "GND")
			(clearance 0.1016)
			(thermal_gap 0.1016)
		)
		(pad "9" thru_hole circle
			(at 1.27 0.762 270)
			(size 0.7112 0.7112)
			(drill 0.4064)
			(layers "*.Cu" "*.Mask")
			(remove_unused_layers no)
			(net "GND")
			(clearance 0.1016)
			(thermal_gap 0.1016)
		)
		(pad "10" thru_hole circle
			(at -0.0254 0.762 270)
			(size 0.7112 0.7112)
			(drill 0.4064)
			(layers "*.Cu" "*.Mask")
			(remove_unused_layers no)
			(net "GND")
			(clearance 0.1016)
			(thermal_gap 0.1016)
		)
		(pad "11" thru_hole circle
			(at -1.27 0.762 270)
			(size 0.7112 0.7112)
			(drill 0.4064)
			(layers "*.Cu" "*.Mask")
			(remove_unused_layers no)
			(net "GND")
			(clearance 0.1016)
			(thermal_gap 0.1016)
		)
		(pad "12" thru_hole circle
			(at -1.27 -0.4572 270)
			(size 0.7112 0.7112)
			(drill 0.4064)
			(layers "*.Cu" "*.Mask")
			(remove_unused_layers no)
			(net "GND")
			(clearance 0.1016)
			(thermal_gap 0.1016)
		)
	)
)
